# BASEBOARD_FAB2 (Tioga Pass) — schematic netlist excerpt (pin names and nets, part order shuffled) for the footprints in the layout excerpt that follows; sources: Cadence DE-HDL packaged netlist, KiCad conversion of Wiwynn_Tioga_Pass_MB.brd

C8L10  CAP_A  47UF 4V 20% X5R  pkg 0603V  page 228 : A = PVDDQ_KLM ; B = GND

(kicad_pcb
	(version 20260206)
	(generator "pcbnew")
	(generator_version "10.0")
	(general
		(thickness 1.6)
		(legacy_teardrops no)
	)
	(paper "A4")
	(title_block
		(title "Wiwynn_Tioga_Pass_MB.brd")
		(comment 1 "Tioga Pass / footprints 4660-4660 of 4770")
	)
	(layers
		(0 "F.Cu" signal "TOP")
		(4 "In1.Cu" signal "L2GND")
		(6 "In2.Cu" signal "L3")
		(8 "In3.Cu" signal "L4GND")
		(10 "In4.Cu" signal "L5")
		(12 "In5.Cu" signal "L6GND")
		(14 "In6.Cu" signal "L7VCC")
		(16 "In7.Cu" signal "L8VCC")
		(18 "In8.Cu" signal "L9GND")
		(20 "In9.Cu" signal "L10")
		(22 "In10.Cu" signal "L11GND")
		(24 "In11.Cu" signal "L12")
		(26 "In12.Cu" signal "L13GND")
		(2 "B.Cu" signal "BOTTOM")
		(9 "F.Adhes" user "F.Adhesive")
		(11 "B.Adhes" user "B.Adhesive")
		(13 "F.Paste" user "Package Geometry/Pastemask Top")
		(15 "B.Paste" user "Package Geometry/Pastemask Bottom")
		(5 "F.SilkS" user "Ref Des/Silkscreen Top")
		(7 "B.SilkS" user "Ref Des/Silkscreen Bottom")
		(1 "F.Mask" user "Board Geometry/Soldermask Top")
		(3 "B.Mask" user "Board Geometry/Soldermask Bottom")
		(17 "Dwgs.User" user "User.Drawings")
		(19 "Cmts.User" user "User.Comments")
		(21 "Eco1.User" user "User.Eco1")
		(23 "Eco2.User" user "User.Eco2")
		(25 "Edge.Cuts" user "Board Geometry/Outline")
		(27 "Margin" user)
		(31 "F.CrtYd" user "Package Geometry/Place Bound Top")
		(29 "B.CrtYd" user "Package Geometry/Place Bound Bottom")
		(35 "F.Fab" user "Ref Des/Assembly Top")
		(33 "B.Fab" user "Ref Des/Assembly Bottom")
	)
	(footprint ""
		(layer "B.Cu")
		(at 80.757268 -145.0086 -90)
		(property "Reference" "C8L10"
			(at -1.848866 0.752348 270)
			(unlocked yes)
			(layer "B.SilkS")
			(effects
				(font
					(size 1.27 0.9652)
					(thickness 0.1524)
				)
				(justify mirror)
			)
		)
		(property "Value" ""
			(at 0 0 90)
			(layer "B.Fab")
			(effects
				(font
					(size 1.27 1.27)
				)
				(justify mirror)
			)
		)
		(duplicate_pad_numbers_are_jumpers no)
		(fp_rect
			(start 0.500126 1.598422)
			(end -0.500126 -0.201422)
			(stroke
				(width 0)
				(type default)
			)
			(fill no)
			(layer "B.CrtYd")
		)
		(fp_line
			(start -0.500126 1.598422)
			(end 0.500126 1.598422)
			(stroke
				(width 0.1)
				(type default)
			)
			(layer "B.Fab")
		)
		(fp_line
			(start 0.500126 1.598422)
			(end 0.500126 -0.201422)
			(stroke
				(width 0.1)
				(type default)
			)
			(layer "B.Fab")
		)
		(fp_line
			(start -0.500126 -0.201422)
			(end -0.500126 1.598422)
			(stroke
				(width 0.1)
				(type default)
			)
			(layer "B.Fab")
		)
		(fp_line
			(start 0.500126 -0.201422)
			(end -0.500126 -0.201422)
			(stroke
				(width 0.1)
				(type default)
			)
			(layer "B.Fab")
		)
		(pad "1" smd rect
			(at 0 0 180)
			(size 0.889 0.9906)
			(layers "B.Cu" "B.Mask" "B.Paste")
			(net "PVDDQ_KLM")
		)
		(pad "2" smd rect
			(at 0 1.397 180)
			(size 0.889 0.9906)
			(layers "B.Cu" "B.Mask" "B.Paste")
			(net "GND")
		)
		(zone
			(layer "B.Cu")
			(hatch none 0.5)
			(connect_pads
				(clearance 0)
			)
			(min_thickness 0.25)
			(keepout
				(tracks not_allowed)
				(vias allowed)
				(pads allowed)
				(copperpour not_allowed)
				(footprints allowed)
			)
			(placement
				(enabled no)
				(sheetname "")
			)
			(fill
				(thermal_gap 0.5)
				(thermal_bridge_width 0.5)
				(island_removal_mode 0)
			)
			(polygon
				(pts
					(xy 79.804768 -144.5133) (xy 80.312768 -144.5133) (xy 80.312768 -145.5039) (xy 79.804768 -145.5039)
				)
			)
		)
		(zone
			(layer "B.Cu")
			(hatch none 0.5)
			(connect_pads
				(clearance 0)
			)
			(min_thickness 0.25)
			(keepout
				(tracks allowed)
				(vias not_allowed)
				(pads allowed)
				(copperpour not_allowed)
				(footprints allowed)
			)
			(placement
				(enabled no)
				(sheetname "")
			)
			(fill
				(thermal_gap 0.5)
				(thermal_bridge_width 0.5)
				(island_removal_mode 0)
			)
			(polygon
				(pts
					(xy 79.804768 -144.5133) (xy 80.312768 -144.5133) (xy 80.312768 -145.5039) (xy 79.804768 -145.5039)
				)
			)
		)
	)
)
